(kicad_pcb
	(version 20241229)
	(generator "pcbnew")
	(generator_version "9.0")
	(general
		(thickness 1.61)
		(legacy_teardrops no)
	)
	(paper "A3")
	(title_block
		(title "SO-DIMM DDR5 Tester")
		(date "2025-11-26")
		(rev "1.3.0")
		(comment 9 "footprints 21-26 of 627")
	)
	(layers
		(0 "F.Cu" signal)
		(4 "In1.Cu" power)
		(6 "In2.Cu" mixed)
		(8 "In3.Cu" power)
		(10 "In4.Cu" mixed)
		(12 "In5.Cu" power)
		(14 "In6.Cu" mixed)
		(16 "In7.Cu" power)
		(18 "In8.Cu" power)
		(20 "In9.Cu" mixed)
		(22 "In10.Cu" power)
		(2 "B.Cu" signal)
		(9 "F.Adhes" user "F.Adhesive")
		(11 "B.Adhes" user "B.Adhesive")
		(13 "F.Paste" user)
		(15 "B.Paste" user)
		(5 "F.SilkS" user "F.Silkscreen")
		(7 "B.SilkS" user "B.Silkscreen")
		(1 "F.Mask" user)
		(3 "B.Mask" user)
		(17 "Dwgs.User" user "User.Drawings")
		(19 "Cmts.User" user "User.Comments")
		(21 "Eco1.User" user "User.Eco1")
		(23 "Eco2.User" user "User.Eco2")
		(25 "Edge.Cuts" user)
		(27 "Margin" user)
		(31 "F.CrtYd" user "F.Courtyard")
		(29 "B.CrtYd" user "B.Courtyard")
		(35 "F.Fab" user)
		(33 "B.Fab" user)
	)
	(footprint "antmicro-footprints:C_0402_1005Metric"
		(layer "F.Cu")
		(at 89.523501 166.175 -90)
		(descr "Capacitor SMD 0402")
		(tags "capacitor SMD 0402")
		(property "Reference" "C117"
			(at 0 -0.699 270)
			(layer "F.SilkS")
			(hide yes)
			(effects
				(font
					(size 0.7 0.7)
					(thickness 0.15)
				)
				(justify left bottom)
			)
		)
		(property "Value" "C_18p_0402"
			(at -1.022927 2.155213 270)
			(layer "F.Fab")
			(effects
				(font
					(size 0.7 0.7)
					(thickness 0.15)
				)
				(justify left bottom)
			)
		)
		(property "Datasheet" "https://product.samsungsem.com/mlcc/CL05C180JB51PN.do"
			(at 0 0 270)
			(layer "F.Fab")
			(hide yes)
			(effects
				(font
					(size 1.27 1.27)
					(thickness 0.15)
				)
			)
		)
		(property "Author" "Antmicro"
			(at -76.651499 255.698501 0)
			(layer "F.Fab")
			(hide yes)
			(effects
				(font
					(size 1 1)
					(thickness 0.15)
				)
			)
		)
		(property "Dielectric" ""
			(at -76.651499 255.698501 0)
			(layer "F.Fab")
			(hide yes)
			(effects
				(font
					(size 1 1)
					(thickness 0.15)
				)
			)
		)
		(property "License" "Apache-2.0"
			(at -76.651499 255.698501 0)
			(layer "F.Fab")
			(hide yes)
			(effects
				(font
					(size 1 1)
					(thickness 0.15)
				)
			)
		)
		(property "MPN" "CL05C180JB51PNC"
			(at -76.651499 255.698501 0)
			(layer "F.Fab")
			(hide yes)
			(effects
				(font
					(size 1 1)
					(thickness 0.15)
				)
			)
		)
		(property "Manufacturer" "Samsung Electro-Mechanics"
			(at -76.651499 255.698501 0)
			(layer "F.Fab")
			(hide yes)
			(effects
				(font
					(size 1 1)
					(thickness 0.15)
				)
			)
		)
		(property "Val" "18p"
			(at -76.651499 255.698501 0)
			(layer "F.Fab")
			(hide yes)
			(effects
				(font
					(size 1 1)
					(thickness 0.15)
				)
			)
		)
		(property "Voltage" ""
			(at -76.651499 255.698501 0)
			(layer "F.Fab")
			(hide yes)
			(effects
				(font
					(size 1 1)
					(thickness 0.15)
				)
			)
		)
		(sheetname "/Debug FTDI/")
		(sheetfile "debug-ftdi.kicad_sch")
		(attr smd)
		(fp_rect
			(start -0.9659 -0.481258)
			(end 0.9649 0.458742)
			(stroke
				(width 0.05)
				(type solid)
			)
			(fill no)
			(layer "F.CrtYd")
		)
		(fp_line
			(start -0.499 0.248)
			(end -0.499 -0.25)
			(stroke
				(width 0.15)
				(type solid)
			)
			(layer "F.Fab")
		)
		(fp_line
			(start 0.499 0.248)
			(end -0.499 0.248)
			(stroke
				(width 0.15)
				(type solid)
			)
			(layer "F.Fab")
		)
		(fp_line
			(start -0.499 -0.25)
			(end 0.499 -0.25)
			(stroke
				(width 0.15)
				(type solid)
			)
			(layer "F.Fab")
		)
		(fp_line
			(start 0.499 -0.25)
			(end 0.499 0.248)
			(stroke
				(width 0.15)
				(type solid)
			)
			(layer "F.Fab")
		)
		(pad "1" smd roundrect
			(at -0.484 0 270)
			(size 0.59 0.64)
			(layers "F.Cu" "F.Mask" "F.Paste")
			(roundrect_rratio 0.25)
			(net 7 "/Debug FTDI/FTDI_XO")
			(pintype "passive")
		)
		(pad "2" smd roundrect
			(at 0.484 0 270)
			(size 0.59 0.64)
			(layers "F.Cu" "F.Mask" "F.Paste")
			(roundrect_rratio 0.25)
			(net 1 "GND")
			(pintype "passive")
		)
	)
	(footprint "antmicro-footprints:R_0402_1005Metric"
		(layer "F.Cu")
		(at 84.620501 165.841 180)
		(descr "Resistor SMD 0402")
		(tags "resistor SMD 0402")
		(property "Reference" "R84"
			(at -1.122484 -0.772697 180)
			(layer "F.SilkS")
			(hide yes)
			(effects
				(font
					(size 0.7 0.7)
					(thickness 0.15)
				)
				(justify left bottom)
			)
		)
		(property "Value" "R_330R_0402"
			(at -1.011843 1.772047 180)
			(layer "F.Fab")
			(effects
				(font
					(size 0.7 0.7)
					(thickness 0.15)
				)
				(justify left bottom)
			)
		)
		(property "Datasheet" "https://www.bourns.com/docs/product-datasheets/cr.pdf"
			(at 0 0 180)
			(layer "F.Fab")
			(hide yes)
			(effects
				(font
					(size 1.27 1.27)
					(thickness 0.15)
				)
			)
		)
		(property "Author" "Antmicro"
			(at 169.241002 331.682 0)
			(layer "F.Fab")
			(hide yes)
			(effects
				(font
					(size 1 1)
					(thickness 0.15)
				)
			)
		)
		(property "License" "Apache-2.0"
			(at 169.241002 331.682 0)
			(layer "F.Fab")
			(hide yes)
			(effects
				(font
					(size 1 1)
					(thickness 0.15)
				)
			)
		)
		(property "MPN" "CR0402-FX-3300GLF"
			(at 169.241002 331.682 0)
			(layer "F.Fab")
			(hide yes)
			(effects
				(font
					(size 1 1)
					(thickness 0.15)
				)
			)
		)
		(property "Manufacturer" "Bourns"
			(at 169.241002 331.682 0)
			(layer "F.Fab")
			(hide yes)
			(effects
				(font
					(size 1 1)
					(thickness 0.15)
				)
			)
		)
		(property "Tolerance" "1%"
			(at 169.241002 331.682 0)
			(layer "F.Fab")
			(hide yes)
			(effects
				(font
					(size 1 1)
					(thickness 0.15)
				)
			)
		)
		(property "Val" "330R"
			(at 169.241002 331.682 0)
			(layer "F.Fab")
			(hide yes)
			(effects
				(font
					(size 1 1)
					(thickness 0.15)
				)
			)
		)
		(sheetname "/HDMI + SD Card/")
		(sheetfile "hdmi-sd-card.kicad_sch")
		(attr smd)
		(fp_rect
			(start -0.93 -0.47)
			(end 0.93 0.47)
			(stroke
				(width 0.05)
				(type solid)
			)
			(fill no)
			(layer "F.CrtYd")
		)
		(fp_rect
			(start -0.5 -0.25)
			(end 0.5 0.25)
			(stroke
				(width 0.15)
				(type solid)
			)
			(fill no)
			(layer "F.Fab")
		)
		(pad "1" smd roundrect
			(at -0.485 0 180)
			(size 0.59 0.64)
			(layers "F.Cu" "F.Mask" "F.Paste")
			(roundrect_rratio 0.25)
			(net 669 "/FPGA bank 16/SD.CD")
			(pintype "passive")
		)
		(pad "2" smd roundrect
			(at 0.485 0 180)
			(size 0.59 0.64)
			(layers "F.Cu" "F.Mask" "F.Paste")
			(roundrect_rratio 0.25)
			(net 330 "Net-(J5-CD_SW1)")
			(pintype "passive")
		)
	)
	(footprint "antmicro-footprints:C_0402_1005Metric"
		(layer "F.Cu")
		(at 91.689001 171.535 90)
		(descr "Capacitor SMD 0402")
		(tags "capacitor SMD 0402")
		(property "Reference" "C112"
			(at 0 -0.699 90)
			(layer "F.SilkS")
			(hide yes)
			(effects
				(font
					(size 0.7 0.7)
					(thickness 0.15)
				)
				(justify left bottom)
			)
		)
		(property "Value" "C_100n_0402"
			(at -1.022927 2.155213 90)
			(layer "F.Fab")
			(effects
				(font
					(size 0.7 0.7)
					(thickness 0.15)
				)
				(justify left bottom)
			)
		)
		(property "Datasheet" "https://www.murata.com/products/productdetail?partno=GRM155R61H104KE14%23"
			(at 0 0 90)
			(layer "F.Fab")
			(hide yes)
			(effects
				(font
					(size 1.27 1.27)
					(thickness 0.15)
				)
			)
		)
		(property "Author" "Antmicro"
			(at 263.224001 79.845999 0)
			(layer "F.Fab")
			(hide yes)
			(effects
				(font
					(size 1 1)
					(thickness 0.15)
				)
			)
		)
		(property "Dielectric" "X5R"
			(at 263.224001 79.845999 0)
			(layer "F.Fab")
			(hide yes)
			(effects
				(font
					(size 1 1)
					(thickness 0.15)
				)
			)
		)
		(property "License" "Apache-2.0"
			(at 263.224001 79.845999 0)
			(layer "F.Fab")
			(hide yes)
			(effects
				(font
					(size 1 1)
					(thickness 0.15)
				)
			)
		)
		(property "MPN" "GRM155R61H104KE14D"
			(at 263.224001 79.845999 0)
			(layer "F.Fab")
			(hide yes)
			(effects
				(font
					(size 1 1)
					(thickness 0.15)
				)
			)
		)
		(property "Manufacturer" "Murata"
			(at 263.224001 79.845999 0)
			(layer "F.Fab")
			(hide yes)
			(effects
				(font
					(size 1 1)
					(thickness 0.15)
				)
			)
		)
		(property "Val" "100n"
			(at 263.224001 79.845999 0)
			(layer "F.Fab")
			(hide yes)
			(effects
				(font
					(size 1 1)
					(thickness 0.15)
				)
			)
		)
		(property "Voltage" "50V"
			(at 263.224001 79.845999 0)
			(layer "F.Fab")
			(hide yes)
			(effects
				(font
					(size 1 1)
					(thickness 0.15)
				)
			)
		)
		(sheetname "/Debug FTDI/")
		(sheetfile "debug-ftdi.kicad_sch")
		(attr smd)
		(fp_rect
			(start -0.9659 -0.481258)
			(end 0.9649 0.458742)
			(stroke
				(width 0.05)
				(type solid)
			)
			(fill no)
			(layer "F.CrtYd")
		)
		(fp_line
			(start 0.499 -0.25)
			(end 0.499 0.248)
			(stroke
				(width 0.15)
				(type solid)
			)
			(layer "F.Fab")
		)
		(fp_line
			(start -0.499 -0.25)
			(end 0.499 -0.25)
			(stroke
				(width 0.15)
				(type solid)
			)
			(layer "F.Fab")
		)
		(fp_line
			(start 0.499 0.248)
			(end -0.499 0.248)
			(stroke
				(width 0.15)
				(type solid)
			)
			(layer "F.Fab")
		)
		(fp_line
			(start -0.499 0.248)
			(end -0.499 -0.25)
			(stroke
				(width 0.15)
				(type solid)
			)
			(layer "F.Fab")
		)
		(pad "1" smd roundrect
			(at -0.484 0 90)
			(size 0.59 0.64)
			(layers "F.Cu" "F.Mask" "F.Paste")
			(roundrect_rratio 0.25)
			(net 5 "/Debug FTDI/FTDI_VPHY")
			(pintype "passive")
		)
		(pad "2" smd roundrect
			(at 0.484 0 90)
			(size 0.59 0.64)
			(layers "F.Cu" "F.Mask" "F.Paste")
			(roundrect_rratio 0.25)
			(net 1 "GND")
			(pintype "passive")
		)
	)
	(footprint "antmicro-footprints:C_0402_1005Metric"
		(layer "F.Cu")
		(at 99.847344 167.542328 90)
		(descr "Capacitor SMD 0402")
		(tags "capacitor SMD 0402")
		(property "Reference" "C118"
			(at 0 -0.699 90)
			(layer "F.SilkS")
			(hide yes)
			(effects
				(font
					(size 0.7 0.7)
					(thickness 0.15)
				)
				(justify left bottom)
			)
		)
		(property "Value" "C_100n_0402"
			(at -1.022927 2.155213 90)
			(layer "F.Fab")
			(effects
				(font
					(size 0.7 0.7)
					(thickness 0.15)
				)
				(justify left bottom)
			)
		)
		(property "Datasheet" "https://www.murata.com/products/productdetail?partno=GRM155R61H104KE14%23"
			(at 0 0 90)
			(layer "F.Fab")
			(hide yes)
			(effects
				(font
					(size 1.27 1.27)
					(thickness 0.15)
				)
			)
		)
		(property "Author" "Antmicro"
			(at 267.389672 67.694984 0)
			(layer "F.Fab")
			(hide yes)
			(effects
				(font
					(size 1 1)
					(thickness 0.15)
				)
			)
		)
		(property "Dielectric" "X5R"
			(at 267.389672 67.694984 0)
			(layer "F.Fab")
			(hide yes)
			(effects
				(font
					(size 1 1)
					(thickness 0.15)
				)
			)
		)
		(property "License" "Apache-2.0"
			(at 267.389672 67.694984 0)
			(layer "F.Fab")
			(hide yes)
			(effects
				(font
					(size 1 1)
					(thickness 0.15)
				)
			)
		)
		(property "MPN" "GRM155R61H104KE14D"
			(at 267.389672 67.694984 0)
			(layer "F.Fab")
			(hide yes)
			(effects
				(font
					(size 1 1)
					(thickness 0.15)
				)
			)
		)
		(property "Manufacturer" "Murata"
			(at 267.389672 67.694984 0)
			(layer "F.Fab")
			(hide yes)
			(effects
				(font
					(size 1 1)
					(thickness 0.15)
				)
			)
		)
		(property "Val" "100n"
			(at 267.389672 67.694984 0)
			(layer "F.Fab")
			(hide yes)
			(effects
				(font
					(size 1 1)
					(thickness 0.15)
				)
			)
		)
		(property "Voltage" "50V"
			(at 267.389672 67.694984 0)
			(layer "F.Fab")
			(hide yes)
			(effects
				(font
					(size 1 1)
					(thickness 0.15)
				)
			)
		)
		(sheetname "/Debug FTDI/")
		(sheetfile "debug-ftdi.kicad_sch")
		(attr smd)
		(fp_rect
			(start -0.9659 -0.481258)
			(end 0.9649 0.458742)
			(stroke
				(width 0.05)
				(type solid)
			)
			(fill no)
			(layer "F.CrtYd")
		)
		(fp_line
			(start 0.499 -0.25)
			(end 0.499 0.248)
			(stroke
				(width 0.15)
				(type solid)
			)
			(layer "F.Fab")
		)
		(fp_line
			(start -0.499 -0.25)
			(end 0.499 -0.25)
			(stroke
				(width 0.15)
				(type solid)
			)
			(layer "F.Fab")
		)
		(fp_line
			(start 0.499 0.248)
			(end -0.499 0.248)
			(stroke
				(width 0.15)
				(type solid)
			)
			(layer "F.Fab")
		)
		(fp_line
			(start -0.499 0.248)
			(end -0.499 -0.25)
			(stroke
				(width 0.15)
				(type solid)
			)
			(layer "F.Fab")
		)
		(pad "1" smd roundrect
			(at -0.484 0 90)
			(size 0.59 0.64)
			(layers "F.Cu" "F.Mask" "F.Paste")
			(roundrect_rratio 0.25)
			(net 6 "/Debug FTDI/FTDI_3V3")
			(pintype "passive")
		)
		(pad "2" smd roundrect
			(at 0.484 0 90)
			(size 0.59 0.64)
			(layers "F.Cu" "F.Mask" "F.Paste")
			(roundrect_rratio 0.25)
			(net 1 "GND")
			(pintype "passive")
		)
	)
	(footprint "antmicro-footprints:C_0402_1005Metric"
		(layer "F.Cu")
		(at 100.927344 167.542328 90)
		(descr "Capacitor SMD 0402")
		(tags "capacitor SMD 0402")
		(property "Reference" "C125"
			(at 0 -0.699 90)
			(layer "F.SilkS")
			(hide yes)
			(effects
				(font
					(size 0.7 0.7)
					(thickness 0.15)
				)
				(justify left bottom)
			)
		)
		(property "Value" "C_100n_0402"
			(at -1.022927 2.155213 90)
			(layer "F.Fab")
			(effects
				(font
					(size 0.7 0.7)
					(thickness 0.15)
				)
				(justify left bottom)
			)
		)
		(property "Datasheet" "https://www.murata.com/products/productdetail?partno=GRM155R61H104KE14%23"
			(at 0 0 90)
			(layer "F.Fab")
			(hide yes)
			(effects
				(font
					(size 1.27 1.27)
					(thickness 0.15)
				)
			)
		)
		(property "Author" "Antmicro"
			(at 268.469672 66.614984 0)
			(layer "F.Fab")
			(hide yes)
			(effects
				(font
					(size 1 1)
					(thickness 0.15)
				)
			)
		)
		(property "Dielectric" "X5R"
			(at 268.469672 66.614984 0)
			(layer "F.Fab")
			(hide yes)
			(effects
				(font
					(size 1 1)
					(thickness 0.15)
				)
			)
		)
		(property "License" "Apache-2.0"
			(at 268.469672 66.614984 0)
			(layer "F.Fab")
			(hide yes)
			(effects
				(font
					(size 1 1)
					(thickness 0.15)
				)
			)
		)
		(property "MPN" "GRM155R61H104KE14D"
			(at 268.469672 66.614984 0)
			(layer "F.Fab")
			(hide yes)
			(effects
				(font
					(size 1 1)
					(thickness 0.15)
				)
			)
		)
		(property "Manufacturer" "Murata"
			(at 268.469672 66.614984 0)
			(layer "F.Fab")
			(hide yes)
			(effects
				(font
					(size 1 1)
					(thickness 0.15)
				)
			)
		)
		(property "Val" "100n"
			(at 268.469672 66.614984 0)
			(layer "F.Fab")
			(hide yes)
			(effects
				(font
					(size 1 1)
					(thickness 0.15)
				)
			)
		)
		(property "Voltage" "50V"
			(at 268.469672 66.614984 0)
			(layer "F.Fab")
			(hide yes)
			(effects
				(font
					(size 1 1)
					(thickness 0.15)
				)
			)
		)
		(sheetname "/Debug FTDI/")
		(sheetfile "debug-ftdi.kicad_sch")
		(attr smd)
		(fp_rect
			(start -0.9659 -0.481258)
			(end 0.9649 0.458742)
			(stroke
				(width 0.05)
				(type solid)
			)
			(fill no)
			(layer "F.CrtYd")
		)
		(fp_line
			(start 0.499 -0.25)
			(end 0.499 0.248)
			(stroke
				(width 0.15)
				(type solid)
			)
			(layer "F.Fab")
		)
		(fp_line
			(start -0.499 -0.25)
			(end 0.499 -0.25)
			(stroke
				(width 0.15)
				(type solid)
			)
			(layer "F.Fab")
		)
		(fp_line
			(start 0.499 0.248)
			(end -0.499 0.248)
			(stroke
				(width 0.15)
				(type solid)
			)
			(layer "F.Fab")
		)
		(fp_line
			(start -0.499 0.248)
			(end -0.499 -0.25)
			(stroke
				(width 0.15)
				(type solid)
			)
			(layer "F.Fab")
		)
		(pad "1" smd roundrect
			(at -0.484 0 90)
			(size 0.59 0.64)
			(layers "F.Cu" "F.Mask" "F.Paste")
			(roundrect_rratio 0.25)
			(net 8 "/Debug FTDI/FTDI_VCORE")
			(pintype "passive")
		)
		(pad "2" smd roundrect
			(at 0.484 0 90)
			(size 0.59 0.64)
			(layers "F.Cu" "F.Mask" "F.Paste")
			(roundrect_rratio 0.25)
			(net 1 "GND")
			(pintype "passive")
		)
	)
	(footprint "antmicro-footprints:C_0402_1005Metric"
		(layer "F.Cu")
		(at 105.468344 173.767328)
		(descr "Capacitor SMD 0402")
		(tags "capacitor SMD 0402")
		(property "Reference" "C120"
			(at 0 -0.699 0)
			(layer "F.SilkS")
			(hide yes)
			(effects
				(font
					(size 0.7 0.7)
					(thickness 0.15)
				)
				(justify left bottom)
			)
		)
		(property "Value" "C_100n_0402"
			(at -1.022927 2.155213 0)
			(layer "F.Fab")
			(effects
				(font
					(size 0.7 0.7)
					(thickness 0.15)
				)
				(justify left bottom)
			)
		)
		(property "Datasheet" "https://www.murata.com/products/productdetail?partno=GRM155R61H104KE14%23"
			(at 0 0 0)
			(layer "F.Fab")
			(hide yes)
			(effects
				(font
					(size 1.27 1.27)
					(thickness 0.15)
				)
			)
		)
		(property "Author" "Antmicro"
			(at 0 0 0)
			(layer "F.Fab")
			(hide yes)
			(effects
				(font
					(size 1 1)
					(thickness 0.15)
				)
			)
		)
		(property "Dielectric" "X5R"
			(at 0 0 0)
			(layer "F.Fab")
			(hide yes)
			(effects
				(font
					(size 1 1)
					(thickness 0.15)
				)
			)
		)
		(property "License" "Apache-2.0"
			(at 0 0 0)
			(layer "F.Fab")
			(hide yes)
			(effects
				(font
					(size 1 1)
					(thickness 0.15)
				)
			)
		)
		(property "MPN" "GRM155R61H104KE14D"
			(at 0 0 0)
			(layer "F.Fab")
			(hide yes)
			(effects
				(font
					(size 1 1)
					(thickness 0.15)
				)
			)
		)
		(property "Manufacturer" "Murata"
			(at 0 0 0)
			(layer "F.Fab")
			(hide yes)
			(effects
				(font
					(size 1 1)
					(thickness 0.15)
				)
			)
		)
		(property "Val" "100n"
			(at 0 0 0)
			(layer "F.Fab")
			(hide yes)
			(effects
				(font
					(size 1 1)
					(thickness 0.15)
				)
			)
		)
		(property "Voltage" "50V"
			(at 0 0 0)
			(layer "F.Fab")
			(hide yes)
			(effects
				(font
					(size 1 1)
					(thickness 0.15)
				)
			)
		)
		(sheetname "/Debug FTDI/")
		(sheetfile "debug-ftdi.kicad_sch")
		(attr smd)
		(fp_rect
			(start -0.9659 -0.481258)
			(end 0.9649 0.458742)
			(stroke
				(width 0.05)
				(type solid)
			)
			(fill no)
			(layer "F.CrtYd")
		)
		(fp_line
			(start -0.499 -0.25)
			(end 0.499 -0.25)
			(stroke
				(width 0.15)
				(type solid)
			)
			(layer "F.Fab")
		)
		(fp_line
			(start -0.499 0.248)
			(end -0.499 -0.25)
			(stroke
				(width 0.15)
				(type solid)
			)
			(layer "F.Fab")
		)
		(fp_line
			(start 0.499 -0.25)
			(end 0.499 0.248)
			(stroke
				(width 0.15)
				(type solid)
			)
			(layer "F.Fab")
		)
		(fp_line
			(start 0.499 0.248)
			(end -0.499 0.248)
			(stroke
				(width 0.15)
				(type solid)
			)
			(layer "F.Fab")
		)
		(pad "1" smd roundrect
			(at -0.484 0)
			(size 0.59 0.64)
			(layers "F.Cu" "F.Mask" "F.Paste")
			(roundrect_rratio 0.25)
			(net 6 "/Debug FTDI/FTDI_3V3")
			(pintype "passive")
		)
		(pad "2" smd roundrect
			(at 0.484 0)
			(size 0.59 0.64)
			(layers "F.Cu" "F.Mask" "F.Paste")
			(roundrect_rratio 0.25)
			(net 1 "GND")
			(pintype "passive")
		)
	)
)
